(kicad_pcb
	(version 20260206)
	(generator "pcbnew")
	(generator_version "10.0")
	(general
		(thickness 1.6)
		(legacy_teardrops no)
	)
	(paper "A4")
	(title_block
		(title "baseboard — 13948-1b.1110WZS1818.brd")
		(comment 1 "Honey Badger (Wiwynn) / footprints 16-20 of 2523")
	)
	(layers
		(0 "F.Cu" signal "TOP")
		(4 "In1.Cu" signal "L2GND")
		(6 "In2.Cu" signal "L3")
		(8 "In3.Cu" signal "L4VCC")
		(10 "In4.Cu" signal "L5VCC")
		(12 "In5.Cu" signal "L6")
		(14 "In6.Cu" signal "L7GND")
		(2 "B.Cu" signal "BOTTOM")
		(9 "F.Adhes" user "F.Adhesive")
		(11 "B.Adhes" user "B.Adhesive")
		(13 "F.Paste" user "Package Geometry/Pastemask Top")
		(15 "B.Paste" user "Package Geometry/Pastemask Bottom")
		(5 "F.SilkS" user "Ref Des/Silkscreen Top")
		(7 "B.SilkS" user "Ref Des/Silkscreen Bottom")
		(1 "F.Mask" user "Board Geometry/Soldermask Top")
		(3 "B.Mask" user "Board Geometry/Soldermask Bottom")
		(17 "Dwgs.User" user "User.Drawings")
		(19 "Cmts.User" user "User.Comments")
		(21 "Eco1.User" user "User.Eco1")
		(23 "Eco2.User" user "User.Eco2")
		(25 "Edge.Cuts" user "Board Geometry/Outline")
		(27 "Margin" user)
		(31 "F.CrtYd" user "Package Geometry/Place Bound Top")
		(29 "B.CrtYd" user "Package Geometry/Place Bound Bottom")
		(35 "F.Fab" user "Ref Des/Assembly Top")
		(33 "B.Fab" user "Ref Des/Assembly Bottom")
	)
	(footprint ""
		(layer "F.Cu")
		(at 188.599318 -138.802872)
		(property "Reference" "SC1109"
			(at 0 0 0)
			(layer "F.SilkS")
			(hide yes)
			(effects
				(font
					(size 1.27 1.27)
				)
			)
		)
		(property "Value" "SCD01U50V2KX-1GP"
			(at 1.1811 -2.7051 0)
			(unlocked yes)
			(layer "F.Fab")
			(hide yes)
			(effects
				(font
					(size 1.016 1.016)
					(thickness 0.1524)
				)
			)
		)
		(property "Device Type" "C402H22"
			(at 1.1811 -4.2291 0)
			(unlocked yes)
			(layer "F.Fab")
			(hide yes)
			(effects
				(font
					(size 1.016 1.016)
					(thickness 0.1524)
				)
			)
		)
		(duplicate_pad_numbers_are_jumpers no)
		(fp_rect
			(start -0.4318 0.9525)
			(end 0.4318 -0.9525)
			(stroke
				(width 0)
				(type default)
			)
			(fill no)
			(layer "F.CrtYd")
		)
		(fp_rect
			(start -0.4318 0.9525)
			(end 0.4318 -0.9525)
			(stroke
				(width 0)
				(type default)
			)
			(fill no)
			(layer "F.Fab")
		)
		(pad "1" smd custom
			(at 0 -0.4445)
			(size 0.1524 0.1524)
			(layers "F.Cu" "F.Mask" "F.Paste")
			(net "P1V8_E")
			(options
				(clearance outline)
				(anchor circle)
			)
			(primitives
				(gr_poly
					(pts
						(arc
							(start 0.3048 -0.2032)
							(mid 0.275042 -0.275042)
							(end 0.2032 -0.3048)
						)
						(arc
							(start -0.2032 -0.3048)
							(mid -0.275042 -0.275042)
							(end -0.3048 -0.2032)
						)
						(arc
							(start -0.3048 0.2032)
							(mid -0.275042 0.275042)
							(end -0.2032 0.3048)
						)
						(arc
							(start 0.2032 0.3048)
							(mid 0.275042 0.275042)
							(end 0.3048 0.2032)
						)
					)
					(width 0)
					(fill yes)
				)
			)
		)
		(pad "2" smd custom
			(at 0 0.4445)
			(size 0.1524 0.1524)
			(layers "F.Cu" "F.Mask" "F.Paste")
			(net "GND")
			(options
				(clearance outline)
				(anchor circle)
			)
			(primitives
				(gr_poly
					(pts
						(arc
							(start 0.3048 -0.2032)
							(mid 0.275042 -0.275042)
							(end 0.2032 -0.3048)
						)
						(arc
							(start -0.2032 -0.3048)
							(mid -0.275042 -0.275042)
							(end -0.3048 -0.2032)
						)
						(arc
							(start -0.3048 0.2032)
							(mid -0.275042 0.275042)
							(end -0.2032 0.3048)
						)
						(arc
							(start 0.2032 0.3048)
							(mid 0.275042 0.275042)
							(end 0.3048 0.2032)
						)
					)
					(width 0)
					(fill yes)
				)
			)
		)
	)
	(footprint ""
		(layer "F.Cu")
		(at 330.191872 -167.585136)
		(property "Reference" "R312"
			(at 0 0 0)
			(layer "F.SilkS")
			(hide yes)
			(effects
				(font
					(size 1.27 1.27)
				)
			)
		)
		(property "Value" "0R2J-2-GP"
			(at 0.064008 -3.993896 0)
			(unlocked yes)
			(layer "F.Fab")
			(hide yes)
			(effects
				(font
					(size 1.016 1.016)
					(thickness 0.1524)
				)
			)
		)
		(property "Device Type" "R402H16"
			(at 0.064008 -5.517896 0)
			(unlocked yes)
			(layer "F.Fab")
			(hide yes)
			(effects
				(font
					(size 1.016 1.016)
					(thickness 0.1524)
				)
			)
		)
		(duplicate_pad_numbers_are_jumpers no)
		(fp_line
			(start -0.508 -0.9398)
			(end -0.508 0.9398)
			(stroke
				(width 0.1524)
				(type default)
			)
			(layer "F.SilkS")
		)
		(fp_line
			(start 0.508 -0.9398)
			(end -0.508 -0.9398)
			(stroke
				(width 0.1524)
				(type default)
			)
			(layer "F.SilkS")
		)
		(fp_rect
			(start -0.508 0.9398)
			(end 0.508 -0.9398)
			(stroke
				(width 0)
				(type default)
			)
			(fill no)
			(layer "F.CrtYd")
		)
		(fp_rect
			(start -0.508 0.9398)
			(end 0.508 -0.9398)
			(stroke
				(width 0)
				(type default)
			)
			(fill no)
			(layer "F.Fab")
		)
		(pad "1" smd custom
			(at 0 -0.4445)
			(size 0.1397 0.1397)
			(layers "F.Cu" "F.Mask" "F.Paste")
			(net "CPU_S_TXD")
			(options
				(clearance outline)
				(anchor circle)
			)
			(primitives
				(gr_poly
					(pts
						(arc
							(start -0.1778 -0.2794)
							(mid -0.249642 -0.249642)
							(end -0.2794 -0.1778)
						)
						(arc
							(start -0.2794 0.1778)
							(mid -0.249642 0.249642)
							(end -0.1778 0.2794)
						)
						(arc
							(start 0.1778 0.2794)
							(mid 0.249642 0.249642)
							(end 0.2794 0.1778)
						)
						(arc
							(start 0.2794 -0.1778)
							(mid 0.249642 -0.249642)
							(end 0.1778 -0.2794)
						)
					)
					(width 0)
					(fill yes)
				)
			)
		)
		(pad "2" smd custom
			(at 0 0.4445)
			(size 0.1397 0.1397)
			(layers "F.Cu" "F.Mask" "F.Paste")
			(net "CPU_UART_TX_R")
			(options
				(clearance outline)
				(anchor circle)
			)
			(primitives
				(gr_poly
					(pts
						(arc
							(start -0.1778 -0.2794)
							(mid -0.249642 -0.249642)
							(end -0.2794 -0.1778)
						)
						(arc
							(start -0.2794 0.1778)
							(mid -0.249642 0.249642)
							(end -0.1778 0.2794)
						)
						(arc
							(start 0.1778 0.2794)
							(mid 0.249642 0.249642)
							(end 0.2794 0.1778)
						)
						(arc
							(start 0.2794 -0.1778)
							(mid 0.249642 -0.249642)
							(end 0.1778 -0.2794)
						)
					)
					(width 0)
					(fill yes)
				)
			)
		)
	)
	(footprint ""
		(layer "F.Cu")
		(at 220.218 -110.363)
		(property "Reference" "PR126"
			(at 0 0 0)
			(layer "F.SilkS")
			(hide yes)
			(effects
				(font
					(size 1.27 1.27)
				)
			)
		)
		(property "Value" "0R2J-2-GP"
			(at 0.064008 -3.993896 0)
			(unlocked yes)
			(layer "F.Fab")
			(hide yes)
			(effects
				(font
					(size 1.016 1.016)
					(thickness 0.1524)
				)
			)
		)
		(property "Device Type" "R402H16"
			(at 0.064008 -5.517896 0)
			(unlocked yes)
			(layer "F.Fab")
			(hide yes)
			(effects
				(font
					(size 1.016 1.016)
					(thickness 0.1524)
				)
			)
		)
		(duplicate_pad_numbers_are_jumpers no)
		(fp_line
			(start -0.508 -0.9398)
			(end -0.508 0.9398)
			(stroke
				(width 0.1524)
				(type default)
			)
			(layer "F.SilkS")
		)
		(fp_line
			(start 0.508 -0.9398)
			(end -0.508 -0.9398)
			(stroke
				(width 0.1524)
				(type default)
			)
			(layer "F.SilkS")
		)
		(fp_rect
			(start -0.508 0.9398)
			(end 0.508 -0.9398)
			(stroke
				(width 0)
				(type default)
			)
			(fill no)
			(layer "F.CrtYd")
		)
		(fp_rect
			(start -0.508 0.9398)
			(end 0.508 -0.9398)
			(stroke
				(width 0)
				(type default)
			)
			(fill no)
			(layer "F.Fab")
		)
		(pad "1" smd custom
			(at 0 -0.4445)
			(size 0.1397 0.1397)
			(layers "F.Cu" "F.Mask" "F.Paste")
			(net "P1V8_C_PG")
			(options
				(clearance outline)
				(anchor circle)
			)
			(primitives
				(gr_poly
					(pts
						(arc
							(start -0.1778 -0.2794)
							(mid -0.249642 -0.249642)
							(end -0.2794 -0.1778)
						)
						(arc
							(start -0.2794 0.1778)
							(mid -0.249642 0.249642)
							(end -0.1778 0.2794)
						)
						(arc
							(start 0.1778 0.2794)
							(mid 0.249642 0.249642)
							(end 0.2794 0.1778)
						)
						(arc
							(start 0.2794 -0.1778)
							(mid 0.249642 -0.249642)
							(end 0.1778 -0.2794)
						)
					)
					(width 0)
					(fill yes)
				)
			)
		)
		(pad "2" smd custom
			(at 0 0.4445)
			(size 0.1397 0.1397)
			(layers "F.Cu" "F.Mask" "F.Paste")
			(net "TPS74801_1V5_C_EN")
			(options
				(clearance outline)
				(anchor circle)
			)
			(primitives
				(gr_poly
					(pts
						(arc
							(start -0.1778 -0.2794)
							(mid -0.249642 -0.249642)
							(end -0.2794 -0.1778)
						)
						(arc
							(start -0.2794 0.1778)
							(mid -0.249642 0.249642)
							(end -0.1778 0.2794)
						)
						(arc
							(start 0.1778 0.2794)
							(mid 0.249642 0.249642)
							(end 0.2794 0.1778)
						)
						(arc
							(start 0.2794 -0.1778)
							(mid 0.249642 -0.249642)
							(end 0.1778 -0.2794)
						)
					)
					(width 0)
					(fill yes)
				)
			)
		)
	)
	(footprint ""
		(layer "F.Cu")
		(at 316.401958 -65.913 90)
		(property "Reference" "R225"
			(at 0 0 90)
			(layer "F.SilkS")
			(hide yes)
			(effects
				(font
					(size 1.27 1.27)
				)
			)
		)
		(property "Value" "0R2J-2-GP"
			(at 0.064008 -3.993896 90)
			(unlocked yes)
			(layer "F.Fab")
			(hide yes)
			(effects
				(font
					(size 1.016 1.016)
					(thickness 0.1524)
				)
			)
		)
		(property "Device Type" "R402H16"
			(at 0.064008 -5.517896 90)
			(unlocked yes)
			(layer "F.Fab")
			(hide yes)
			(effects
				(font
					(size 1.016 1.016)
					(thickness 0.1524)
				)
			)
		)
		(duplicate_pad_numbers_are_jumpers no)
		(fp_line
			(start 0.508 -0.9398)
			(end -0.508 -0.9398)
			(stroke
				(width 0.1524)
				(type default)
			)
			(layer "F.SilkS")
		)
		(fp_line
			(start -0.508 -0.9398)
			(end -0.508 0.9398)
			(stroke
				(width 0.1524)
				(type default)
			)
			(layer "F.SilkS")
		)
		(fp_rect
			(start -0.508 0.9398)
			(end 0.508 -0.9398)
			(stroke
				(width 0)
				(type default)
			)
			(fill no)
			(layer "F.CrtYd")
		)
		(fp_rect
			(start -0.508 0.9398)
			(end 0.508 -0.9398)
			(stroke
				(width 0)
				(type default)
			)
			(fill no)
			(layer "F.Fab")
		)
		(pad "1" smd custom
			(at 0 -0.4445 90)
			(size 0.1397 0.1397)
			(layers "F.Cu" "F.Mask" "F.Paste")
			(net "NCSI_10G_RXD1_R")
			(options
				(clearance outline)
				(anchor circle)
			)
			(primitives
				(gr_poly
					(pts
						(arc
							(start -0.1778 -0.2794)
							(mid -0.249642 -0.249642)
							(end -0.2794 -0.1778)
						)
						(arc
							(start -0.2794 0.1778)
							(mid -0.249642 0.249642)
							(end -0.1778 0.2794)
						)
						(arc
							(start 0.1778 0.2794)
							(mid 0.249642 0.249642)
							(end 0.2794 0.1778)
						)
						(arc
							(start 0.2794 -0.1778)
							(mid 0.249642 -0.249642)
							(end 0.1778 -0.2794)
						)
					)
					(width 0)
					(fill yes)
				)
			)
		)
		(pad "2" smd custom
			(at 0 0.4445 90)
			(size 0.1397 0.1397)
			(layers "F.Cu" "F.Mask" "F.Paste")
			(net "NCSI_10G_RXD1")
			(options
				(clearance outline)
				(anchor circle)
			)
			(primitives
				(gr_poly
					(pts
						(arc
							(start -0.1778 -0.2794)
							(mid -0.249642 -0.249642)
							(end -0.2794 -0.1778)
						)
						(arc
							(start -0.2794 0.1778)
							(mid -0.249642 0.249642)
							(end -0.1778 0.2794)
						)
						(arc
							(start 0.1778 0.2794)
							(mid 0.249642 0.249642)
							(end 0.2794 0.1778)
						)
						(arc
							(start 0.2794 -0.1778)
							(mid 0.249642 -0.249642)
							(end 0.1778 -0.2794)
						)
					)
					(width 0)
					(fill yes)
				)
			)
		)
	)
	(footprint ""
		(layer "F.Cu")
		(at 82.41919 -62.832488 180)
		(property "Reference" "SL2"
			(at 0 0 180)
			(layer "F.SilkS")
			(hide yes)
			(effects
				(font
					(size 1.27 1.27)
				)
			)
		)
		(property "Value" "MPZ2012S601AT-GP"
			(at 0 -4.2418 180)
			(unlocked yes)
			(layer "F.Fab")
			(hide yes)
			(effects
				(font
					(size 1.016 1.016)
					(thickness 0.1524)
				)
			)
		)
		(property "Device Type" "L805H42"
			(at 0 -5.7912 180)
			(unlocked yes)
			(layer "F.Fab")
			(hide yes)
			(effects
				(font
					(size 1.016 1.016)
					(thickness 0.1524)
				)
			)
		)
		(duplicate_pad_numbers_are_jumpers no)
		(fp_line
			(start 0.889 1.7018)
			(end -0.889 1.7018)
			(stroke
				(width 0.1524)
				(type default)
			)
			(layer "F.SilkS")
		)
		(fp_line
			(start 0.889 -1.7018)
			(end 0.889 1.7018)
			(stroke
				(width 0.1524)
				(type default)
			)
			(layer "F.SilkS")
		)
		(fp_line
			(start -0.889 1.7018)
			(end -0.889 -1.7018)
			(stroke
				(width 0.1524)
				(type default)
			)
			(layer "F.SilkS")
		)
		(fp_line
			(start -0.889 -1.7018)
			(end 0.889 -1.7018)
			(stroke
				(width 0.1524)
				(type default)
			)
			(layer "F.SilkS")
		)
		(fp_rect
			(start -0.9652 1.778)
			(end 0.9652 -1.778)
			(stroke
				(width 0)
				(type default)
			)
			(fill no)
			(layer "F.CrtYd")
		)
		(fp_rect
			(start -0.9652 1.778)
			(end 0.9652 -1.778)
			(stroke
				(width 0)
				(type default)
			)
			(fill no)
			(layer "F.Fab")
		)
		(pad "1" smd rect
			(at 0 -0.9652 180)
			(size 1.397 1.143)
			(layers "F.Cu" "F.Mask" "F.Paste")
			(net "SYS_PLL_VDD")
		)
		(pad "2" smd rect
			(at 0 0.9652 180)
			(size 1.397 1.143)
			(layers "F.Cu" "F.Mask" "F.Paste")
			(net "P1V8_C")
		)
	)
)
